# T6G (Grand Teton) — schematic netlist excerpt (pin names and nets, part order shuffled) for the footprints in the layout excerpt that follows; sources: Cadence DE-HDL packaged netlist, KiCad conversion of 04192023_DAF0TMB3IC0_F0TG_MB_C_brd_V02_OCP.brd

PR491  Q_RES  1.5 1% EMPTY  pkg 0402LF  page 223 : A = SW_PVDDIO_P1_SW4_RC ; B = GND

PL29  Q_INDUCTOR4P_14  150NH IND  pkg L_TLM117513Q-151QL_11X7-5XA  page 211
  \1\  = SW_PVDDCR_CPU0_P1_SW2
  \2\  = IND_CPU0_P1_CPL1
  \3\  = IND_CPU0_P1_CPL2
  \4\  = PVDDCR_CPU0_P1

(kicad_pcb
	(version 20260206)
	(generator "pcbnew")
	(generator_version "10.0")
	(general
		(thickness 1.6)
		(legacy_teardrops no)
	)
	(paper "A4")
	(title_block
		(title "04192023_DAF0TMB3IC0_F0TG_MB_C_brd_V02_OCP.brd")
		(comment 1 "Grand Teton / footprints 38-39 of 8354")
	)
	(layers
		(0 "F.Cu" signal "TOP")
		(4 "In1.Cu" signal "GND")
		(6 "In2.Cu" signal "IN1")
		(8 "In3.Cu" signal "GND1")
		(10 "In4.Cu" signal "IN2")
		(12 "In5.Cu" signal "GND2")
		(14 "In6.Cu" signal "IN3")
		(16 "In7.Cu" signal "GND3")
		(18 "In8.Cu" signal "VCC")
		(20 "In9.Cu" signal "VCC1")
		(22 "In10.Cu" signal "GND4")
		(24 "In11.Cu" signal "IN4")
		(26 "In12.Cu" signal "GND5")
		(28 "In13.Cu" signal "IN5")
		(30 "In14.Cu" signal "GND6")
		(32 "In15.Cu" signal "IN6")
		(34 "In16.Cu" signal "GND7")
		(2 "B.Cu" signal "BOTTOM")
		(9 "F.Adhes" user "F.Adhesive")
		(11 "B.Adhes" user "B.Adhesive")
		(13 "F.Paste" user "Package Geometry/Pastemask Top")
		(15 "B.Paste" user "Package Geometry/Pastemask Bottom")
		(5 "F.SilkS" user "Ref Des/Silkscreen Top")
		(7 "B.SilkS" user "Ref Des/Silkscreen Bottom")
		(1 "F.Mask" user "Board Geometry/Soldermask Top")
		(3 "B.Mask" user "Board Geometry/Soldermask Bottom")
		(17 "Dwgs.User" user "User.Drawings")
		(19 "Cmts.User" user "User.Comments")
		(21 "Eco1.User" user "User.Eco1")
		(23 "Eco2.User" user "User.Eco2")
		(25 "Edge.Cuts" user "Board Geometry/Outline")
		(27 "Margin" user)
		(31 "F.CrtYd" user "Package Geometry/Place Bound Top")
		(29 "B.CrtYd" user "Package Geometry/Place Bound Bottom")
		(35 "F.Fab" user "Ref Des/Assembly Top")
		(33 "B.Fab" user "Ref Des/Assembly Bottom")
	)
	(footprint ""
		(layer "F.Cu")
		(at 24.923496 -344.986864 90)
		(property "Reference" "PR491"
			(at 0 0 90)
			(layer "F.SilkS")
			(hide yes)
			(effects
				(font
					(size 1.27 1.27)
				)
			)
		)
		(property "Value" ""
			(at 0 0 90)
			(layer "F.Fab")
			(effects
				(font
					(size 1.27 1.27)
				)
			)
		)
		(duplicate_pad_numbers_are_jumpers no)
		(fp_line
			(start 0.7874 -0.4064)
			(end 0.7874 0.4064)
			(stroke
				(width 0.1524)
				(type default)
			)
			(layer "F.SilkS")
		)
		(fp_line
			(start -0.7874 -0.4064)
			(end 0.7874 -0.4064)
			(stroke
				(width 0.1524)
				(type default)
			)
			(layer "F.SilkS")
		)
		(fp_line
			(start 0.7874 0.4064)
			(end -0.7874 0.4064)
			(stroke
				(width 0.1524)
				(type default)
			)
			(layer "F.SilkS")
		)
		(fp_line
			(start -0.7874 0.4064)
			(end -0.7874 -0.4064)
			(stroke
				(width 0.1524)
				(type default)
			)
			(layer "F.SilkS")
		)
		(fp_line
			(start -0.12065 -0.305054)
			(end -0.12065 -0.2794)
			(stroke
				(width 0.1)
				(type default)
			)
			(layer "F.Fab")
		)
		(fp_line
			(start -0.67945 -0.305054)
			(end -0.12065 -0.305054)
			(stroke
				(width 0.1)
				(type default)
			)
			(layer "F.Fab")
		)
		(fp_line
			(start 0.67945 -0.3048)
			(end 0.67945 0.3048)
			(stroke
				(width 0.1)
				(type default)
			)
			(layer "F.Fab")
		)
		(fp_line
			(start 0.12065 -0.3048)
			(end 0.67945 -0.3048)
			(stroke
				(width 0.1)
				(type default)
			)
			(layer "F.Fab")
		)
		(fp_line
			(start 0.12065 -0.2794)
			(end 0.12065 -0.3048)
			(stroke
				(width 0.1)
				(type default)
			)
			(layer "F.Fab")
		)
		(fp_line
			(start -0.12065 -0.2794)
			(end 0.12065 -0.2794)
			(stroke
				(width 0.1)
				(type default)
			)
			(layer "F.Fab")
		)
		(fp_line
			(start 0.120396 0.2794)
			(end -0.12065 0.2794)
			(stroke
				(width 0.1)
				(type default)
			)
			(layer "F.Fab")
		)
		(fp_line
			(start -0.12065 0.2794)
			(end -0.12065 0.3048)
			(stroke
				(width 0.1)
				(type default)
			)
			(layer "F.Fab")
		)
		(fp_line
			(start 0.67945 0.3048)
			(end 0.120396 0.3048)
			(stroke
				(width 0.1)
				(type default)
			)
			(layer "F.Fab")
		)
		(fp_line
			(start 0.120396 0.3048)
			(end 0.120396 0.2794)
			(stroke
				(width 0.1)
				(type default)
			)
			(layer "F.Fab")
		)
		(fp_line
			(start -0.12065 0.3048)
			(end -0.67945 0.3048)
			(stroke
				(width 0.1)
				(type default)
			)
			(layer "F.Fab")
		)
		(fp_line
			(start -0.67945 0.3048)
			(end -0.67945 -0.305054)
			(stroke
				(width 0.1)
				(type default)
			)
			(layer "F.Fab")
		)
		(pad "1" smd circle
			(at -0.40005 0 90)
			(size 0 0)
			(layers "F.Cu" "F.Mask" "F.Paste")
			(net "SW_PVDDIO_P1_SW4_RC")
		)
		(pad "2" smd circle
			(at 0.40005 0 90)
			(size 0 0)
			(layers "F.Cu" "F.Mask" "F.Paste")
			(net "GND")
		)
	)
	(footprint ""
		(layer "F.Cu")
		(at 90.563954 -192.038732 180)
		(property "Reference" "PL29"
			(at -14.231112 3.341878 90)
			(unlocked yes)
			(layer "F.SilkS")
			(effects
				(font
					(size 0.7874 0.5842)
					(thickness 0.1524)
				)
				(justify left)
			)
		)
		(property "Value" ""
			(at 0 0 180)
			(layer "F.Fab")
			(effects
				(font
					(size 1.27 1.27)
				)
			)
		)
		(duplicate_pad_numbers_are_jumpers no)
		(fp_line
			(start 3.750056 5.500116)
			(end 3.750056 -5.500116)
			(stroke
				(width 0.1524)
				(type default)
			)
			(layer "F.SilkS")
		)
		(fp_line
			(start 3.750056 -5.500116)
			(end 2.393442 -5.500116)
			(stroke
				(width 0.1524)
				(type default)
			)
			(layer "F.SilkS")
		)
		(fp_line
			(start 2.393442 5.500116)
			(end 3.750056 5.500116)
			(stroke
				(width 0.1524)
				(type default)
			)
			(layer "F.SilkS")
		)
		(fp_line
			(start -2.393442 5.500116)
			(end -3.750056 5.500116)
			(stroke
				(width 0.1524)
				(type default)
			)
			(layer "F.SilkS")
		)
		(fp_line
			(start -3.750056 5.500116)
			(end -3.750056 -5.500116)
			(stroke
				(width 0.1524)
				(type default)
			)
			(layer "F.SilkS")
		)
		(fp_line
			(start -3.750056 -5.500116)
			(end -2.393442 -5.500116)
			(stroke
				(width 0.1524)
				(type default)
			)
			(layer "F.SilkS")
		)
		(fp_poly
			(pts
				(xy -3.9116 -4.249928) (xy -4.445 -3.983228) (xy -4.445 -4.516628)
			)
			(stroke
				(width 0)
				(type default)
			)
			(fill yes)
			(layer "F.SilkS")
		)
		(fp_line
			(start 3.750056 5.500116)
			(end 3.750056 -5.500116)
			(stroke
				(width 0.1)
				(type default)
			)
			(layer "F.Fab")
		)
		(fp_line
			(start 3.750056 -5.500116)
			(end -3.750056 -5.500116)
			(stroke
				(width 0.1)
				(type default)
			)
			(layer "F.Fab")
		)
		(fp_line
			(start -3.750056 5.500116)
			(end 3.750056 5.500116)
			(stroke
				(width 0.1)
				(type default)
			)
			(layer "F.Fab")
		)
		(fp_line
			(start -3.750056 -5.500116)
			(end -3.750056 5.500116)
			(stroke
				(width 0.1)
				(type default)
			)
			(layer "F.Fab")
		)
		(fp_poly
			(pts
				(xy -4.9276 -4.757928) (xy -4.9276 -3.741928) (xy -3.9116 -4.249928)
			)
			(stroke
				(width 0)
				(type default)
			)
			(fill yes)
			(layer "F.Fab")
		)
		(pad "1" smd rect
			(at 0 -4.249928 90)
			(size 2.413 4.5212)
			(layers "F.Cu" "F.Mask" "F.Paste")
			(net "SW_PVDDCR_CPU0_P1_SW2")
		)
		(pad "2" smd rect
			(at 0 -1.175004 90)
			(size 1.3716 4.5212)
			(layers "F.Cu" "F.Mask" "F.Paste")
			(net "IND_CPU0_P1_CPL1")
		)
		(pad "3" smd rect
			(at 0 1.175004 90)
			(size 1.3716 4.5212)
			(layers "F.Cu" "F.Mask" "F.Paste")
			(net "IND_CPU0_P1_CPL2")
		)
		(pad "4" smd rect
			(at 0 4.249928 90)
			(size 2.413 4.5212)
			(layers "F.Cu" "F.Mask" "F.Paste")
			(net "PVDDCR_CPU0_P1")
		)
	)
)
